(kicad_pcb
	(version 20260206)
	(generator "pcbnew")
	(generator_version "10.0")
	(general
		(thickness 1.6)
		(legacy_teardrops no)
	)
	(paper "A4")
	(title_block
		(title "Bryce Canyon_F.DPB_16315-1-OCP.brd")
		(comment 1 "Bryce Canyon / footprints 2157-2163 of 2223")
	)
	(layers
		(0 "F.Cu" signal "TOP")
		(4 "In1.Cu" signal "L2GND")
		(6 "In2.Cu" signal "L3")
		(8 "In3.Cu" signal "L4GND")
		(10 "In4.Cu" signal "L5")
		(12 "In5.Cu" signal "L6VCC")
		(14 "In6.Cu" signal "L7VCC")
		(16 "In7.Cu" signal "L8")
		(18 "In8.Cu" signal "L9GND")
		(20 "In9.Cu" signal "L10")
		(22 "In10.Cu" signal "L11GND")
		(2 "B.Cu" signal "BOTTOM")
		(9 "F.Adhes" user "F.Adhesive")
		(11 "B.Adhes" user "B.Adhesive")
		(13 "F.Paste" user "Package Geometry/Pastemask Top")
		(15 "B.Paste" user "Package Geometry/Pastemask Bottom")
		(5 "F.SilkS" user "Ref Des/Silkscreen Top")
		(7 "B.SilkS" user "Ref Des/Silkscreen Bottom")
		(1 "F.Mask" user "Board Geometry/Soldermask Top")
		(3 "B.Mask" user "Board Geometry/Soldermask Bottom")
		(17 "Dwgs.User" user "User.Drawings")
		(19 "Cmts.User" user "User.Comments")
		(21 "Eco1.User" user "User.Eco1")
		(23 "Eco2.User" user "User.Eco2")
		(25 "Edge.Cuts" user "Board Geometry/Outline")
		(27 "Margin" user)
		(31 "F.CrtYd" user "Package Geometry/Place Bound Top")
		(29 "B.CrtYd" user "Package Geometry/Place Bound Bottom")
		(35 "F.Fab" user "Ref Des/Assembly Top")
		(33 "B.Fab" user "Ref Des/Assembly Bottom")
	)
	(footprint ""
		(layer "B.Cu")
		(at 465.6328 -254.0254 180)
		(property "Reference" "TC7"
			(at 0 0 0)
			(layer "B.SilkS")
			(hide yes)
			(effects
				(font
					(size 1.27 1.27)
				)
				(justify mirror)
			)
		)
		(property "Value" "ST220U10VDM-LGP"
			(at 0 -9.6012 180)
			(unlocked yes)
			(layer "B.Fab")
			(hide yes)
			(effects
				(font
					(size 1.016 1.016)
					(thickness 0.1524)
				)
				(justify mirror)
			)
		)
		(property "Device Type" "CT7343H119"
			(at 0 -11.1252 180)
			(unlocked yes)
			(layer "B.Fab")
			(hide yes)
			(effects
				(font
					(size 1.016 1.016)
					(thickness 0.1524)
				)
				(justify mirror)
			)
		)
		(duplicate_pad_numbers_are_jumpers no)
		(fp_line
			(start 2.286 4.8768)
			(end 2.286 2.032)
			(stroke
				(width 0.1524)
				(type default)
			)
			(layer "B.SilkS")
		)
		(fp_line
			(start 2.286 -4.8768)
			(end 2.286 -2.032)
			(stroke
				(width 0.1524)
				(type default)
			)
			(layer "B.SilkS")
		)
		(fp_line
			(start -2.1082 -4.699)
			(end 2.1082 -4.699)
			(stroke
				(width 0.508)
				(type default)
			)
			(layer "B.SilkS")
		)
		(fp_line
			(start -2.286 4.8768)
			(end 2.286 4.8768)
			(stroke
				(width 0.1524)
				(type default)
			)
			(layer "B.SilkS")
		)
		(fp_line
			(start -2.286 2.032)
			(end -2.286 4.8768)
			(stroke
				(width 0.1524)
				(type default)
			)
			(layer "B.SilkS")
		)
		(fp_line
			(start -2.286 -2.032)
			(end -2.286 -4.8768)
			(stroke
				(width 0.1524)
				(type default)
			)
			(layer "B.SilkS")
		)
		(fp_line
			(start -2.286 -4.8768)
			(end 2.286 -4.8768)
			(stroke
				(width 0.1524)
				(type default)
			)
			(layer "B.SilkS")
		)
		(fp_rect
			(start 2.1463 3.6449)
			(end -2.1463 -3.6449)
			(stroke
				(width 0)
				(type default)
			)
			(fill no)
			(layer "B.CrtYd")
		)
		(fp_poly
			(pts
				(xy 2.54 4.953) (xy 2.54 4.2926) (xy 3.81 4.2926) (xy 3.81 -4.2926) (xy 2.54 -4.2926) (xy 2.54 -4.953)
				(xy -2.54 -4.953) (xy -2.54 -4.2926) (xy -3.81 -4.2926) (xy -3.81 -1.6256) (xy -2.1463 -1.6256)
				(xy -2.1463 -3.6449) (xy 2.1463 -3.6449) (xy 2.1463 3.6449) (xy -2.1463 3.6449) (xy -2.1463 -1.6129)
				(xy -3.81 -1.6129) (xy -3.81 4.2926) (xy -2.54 4.2926) (xy -2.54 4.953)
			)
			(stroke
				(width 0)
				(type default)
			)
			(fill no)
			(layer "B.CrtYd")
		)
		(fp_rect
			(start 3.81 4.2926)
			(end 2.54 -4.2926)
			(stroke
				(width 0)
				(type default)
			)
			(fill no)
			(layer "B.Fab")
		)
		(fp_rect
			(start 2.54 4.953)
			(end -2.54 -4.953)
			(stroke
				(width 0)
				(type default)
			)
			(fill no)
			(layer "B.Fab")
		)
		(fp_rect
			(start -2.54 4.2926)
			(end -3.81 -4.2926)
			(stroke
				(width 0)
				(type default)
			)
			(fill no)
			(layer "B.Fab")
		)
		(pad "1" smd rect
			(at 0 -3.1496)
			(size 2.413 2.286)
			(layers "B.Cu" "B.Mask" "B.Paste")
			(net "P5V_A_3")
		)
		(pad "2" smd rect
			(at 0 3.1496)
			(size 2.413 2.286)
			(layers "B.Cu" "B.Mask" "B.Paste")
			(net "GND")
		)
		(zone
			(layer "B.Cu")
			(hatch none 0.5)
			(connect_pads
				(clearance 0)
			)
			(min_thickness 0.25)
			(keepout
				(tracks allowed)
				(vias not_allowed)
				(pads allowed)
				(copperpour not_allowed)
				(footprints allowed)
			)
			(placement
				(enabled no)
				(sheetname "")
			)
			(fill
				(thermal_gap 0.5)
				(thermal_bridge_width 0.5)
				(island_removal_mode 0)
			)
			(polygon
				(pts
					(xy 464.1215 -258.6228) (xy 467.1441 -258.6228) (xy 467.1441 -255.7272) (xy 467.1441 -255.397)
					(xy 464.1215 -255.397) (xy 464.1215 -255.7272)
				)
			)
		)
		(zone
			(layer "B.Cu")
			(hatch none 0.5)
			(connect_pads
				(clearance 0)
			)
			(min_thickness 0.25)
			(keepout
				(tracks allowed)
				(vias not_allowed)
				(pads allowed)
				(copperpour not_allowed)
				(footprints allowed)
			)
			(placement
				(enabled no)
				(sheetname "")
			)
			(fill
				(thermal_gap 0.5)
				(thermal_bridge_width 0.5)
				(island_removal_mode 0)
			)
			(polygon
				(pts
					(xy 467.1441 -252.3363) (xy 467.1441 -249.428) (xy 464.1215 -249.428) (xy 464.1215 -252.3236) (xy 464.1215 -252.6538)
					(xy 467.1441 -252.6538)
				)
			)
		)
	)
	(footprint ""
		(layer "B.Cu")
		(at 269.5702 -102.7938 -90)
		(property "Reference" "C520"
			(at 0 0 90)
			(layer "B.SilkS")
			(hide yes)
			(effects
				(font
					(size 1.27 1.27)
				)
				(justify mirror)
			)
		)
		(property "Value" "SC22U25V6KX-2-GP-U"
			(at 2.860802 -5.279644 270)
			(unlocked yes)
			(layer "B.Fab")
			(hide yes)
			(effects
				(font
					(size 1.016 1.016)
					(thickness 0.1524)
				)
				(justify mirror)
			)
		)
		(property "Device Type" "C1206-TO0D3H75"
			(at 2.860802 -6.803644 270)
			(unlocked yes)
			(layer "B.Fab")
			(hide yes)
			(effects
				(font
					(size 1.016 1.016)
					(thickness 0.1524)
				)
				(justify mirror)
			)
		)
		(duplicate_pad_numbers_are_jumpers no)
		(fp_line
			(start -1.3081 2.3749)
			(end 1.3081 2.3749)
			(stroke
				(width 0.1524)
				(type default)
			)
			(layer "B.SilkS")
		)
		(fp_line
			(start 1.3081 2.3749)
			(end 1.3081 -2.3749)
			(stroke
				(width 0.1524)
				(type default)
			)
			(layer "B.SilkS")
		)
		(fp_line
			(start -1.3081 -2.3749)
			(end -1.3081 2.3749)
			(stroke
				(width 0.1524)
				(type default)
			)
			(layer "B.SilkS")
		)
		(fp_line
			(start 1.3081 -2.3749)
			(end -1.3081 -2.3749)
			(stroke
				(width 0.1524)
				(type default)
			)
			(layer "B.SilkS")
		)
		(fp_rect
			(start 0.8001 1.6002)
			(end -0.8001 -1.6002)
			(stroke
				(width 0)
				(type default)
			)
			(fill no)
			(layer "B.CrtYd")
		)
		(fp_poly
			(pts
				(xy 1.5621 2.4511) (xy 1.5621 1.6002) (xy -0.8001 1.6002) (xy -0.8001 -1.6002) (xy 0.8001 -1.6002)
				(xy 0.8001 1.5875) (xy 1.5621 1.5875) (xy 1.5621 -2.4511) (xy -1.5621 -2.4511) (xy -1.5621 2.4511)
			)
			(stroke
				(width 0)
				(type default)
			)
			(fill no)
			(layer "B.CrtYd")
		)
		(fp_rect
			(start 1.5621 2.4511)
			(end -1.5621 -2.4511)
			(stroke
				(width 0)
				(type default)
			)
			(fill no)
			(layer "B.Fab")
		)
		(pad "1" smd rect
			(at 0 -1.392936 90)
			(size 2.1082 1.4478)
			(layers "B.Cu" "B.Mask" "B.Paste")
			(net "P12V_B_COMP")
		)
		(pad "2" smd rect
			(at 0 1.392936 90)
			(size 2.1082 1.4478)
			(layers "B.Cu" "B.Mask" "B.Paste")
			(net "GND")
		)
	)
	(footprint ""
		(layer "B.Cu")
		(at 54.1528 -252.1966 180)
		(property "Reference" "C612"
			(at 0 0 0)
			(layer "B.SilkS")
			(hide yes)
			(effects
				(font
					(size 1.27 1.27)
				)
				(justify mirror)
			)
		)
		(property "Value" "SC10U16V5KX-7-GP-U"
			(at 0.0762 -6.1214 180)
			(unlocked yes)
			(layer "B.Fab")
			(hide yes)
			(effects
				(font
					(size 1.016 1.016)
					(thickness 0.1524)
				)
				(justify mirror)
			)
		)
		(property "Device Type" "C805H58"
			(at 0.0762 -8.1534 180)
			(unlocked yes)
			(layer "B.Fab")
			(hide yes)
			(effects
				(font
					(size 1.016 1.016)
					(thickness 0.1524)
				)
				(justify mirror)
			)
		)
		(duplicate_pad_numbers_are_jumpers no)
		(fp_line
			(start -0.635 0)
			(end 0.635 0)
			(stroke
				(width 0.508)
				(type default)
			)
			(layer "B.SilkS")
		)
		(fp_rect
			(start 0.9652 1.778)
			(end -0.9652 -1.778)
			(stroke
				(width 0)
				(type default)
			)
			(fill no)
			(layer "B.CrtYd")
		)
		(fp_poly
			(pts
				(xy 0.9652 -1.778) (xy -0.9652 -1.778) (xy -0.9652 1.778) (xy 0.9652 1.778)
			)
			(stroke
				(width 0)
				(type default)
			)
			(fill no)
			(layer "B.Fab")
		)
		(pad "1" smd rect
			(at 0 -0.9652)
			(size 1.397 1.143)
			(layers "B.Cu" "B.Mask" "B.Paste")
			(net "P5V_A_1")
		)
		(pad "2" smd rect
			(at 0 0.9652)
			(size 1.397 1.143)
			(layers "B.Cu" "B.Mask" "B.Paste")
			(net "GND")
		)
	)
	(footprint ""
		(layer "B.Cu")
		(at 469.138 -233.299 90)
		(property "Reference" "R1269"
			(at 0 0 90)
			(layer "B.SilkS")
			(hide yes)
			(effects
				(font
					(size 1.27 1.27)
				)
				(justify mirror)
			)
		)
		(property "Value" "3D01R5F-GP"
			(at 0 -8.9535 90)
			(unlocked yes)
			(layer "B.Fab")
			(hide yes)
			(effects
				(font
					(size 1.27 1.016)
					(thickness 0.1524)
				)
				(justify mirror)
			)
		)
		(property "Device Type" "R805H24"
			(at 0 -10.6299 90)
			(unlocked yes)
			(layer "B.Fab")
			(hide yes)
			(effects
				(font
					(size 1.27 1.016)
					(thickness 0.1524)
				)
				(justify mirror)
			)
		)
		(duplicate_pad_numbers_are_jumpers no)
		(fp_line
			(start 0.889 -1.7018)
			(end 0.889 0.2794)
			(stroke
				(width 0.1524)
				(type default)
			)
			(layer "B.SilkS")
		)
		(fp_line
			(start -0.889 -1.7018)
			(end 0.889 -1.7018)
			(stroke
				(width 0.1524)
				(type default)
			)
			(layer "B.SilkS")
		)
		(fp_line
			(start -0.889 -1.7018)
			(end -0.889 -0.381)
			(stroke
				(width 0.1524)
				(type default)
			)
			(layer "B.SilkS")
		)
		(fp_line
			(start 0.889 0.0762)
			(end 0.889 1.7018)
			(stroke
				(width 0.1524)
				(type default)
			)
			(layer "B.SilkS")
		)
		(fp_line
			(start 0.889 1.7018)
			(end -0.889 1.7018)
			(stroke
				(width 0.1524)
				(type default)
			)
			(layer "B.SilkS")
		)
		(fp_line
			(start -0.889 1.7018)
			(end -0.889 -0.508)
			(stroke
				(width 0.1524)
				(type default)
			)
			(layer "B.SilkS")
		)
		(fp_poly
			(pts
				(xy -0.9652 -1.778) (xy -0.9652 1.778) (xy 0.9652 1.778) (xy 0.9652 -1.778)
			)
			(stroke
				(width 0)
				(type default)
			)
			(fill no)
			(layer "B.CrtYd")
		)
		(fp_rect
			(start 0.9652 1.778)
			(end -0.9652 -1.778)
			(stroke
				(width 0)
				(type default)
			)
			(fill no)
			(layer "B.Fab")
		)
		(pad "1" smd rect
			(at 0 -0.9652 270)
			(size 1.397 1.143)
			(layers "B.Cu" "B.Mask" "B.Paste")
			(net "P5V_D_SNB")
		)
		(pad "2" smd rect
			(at 0 0.9652 270)
			(size 1.397 1.143)
			(layers "B.Cu" "B.Mask" "B.Paste")
			(net "GND")
		)
	)
	(footprint ""
		(layer "B.Cu")
		(at 48.6156 -244.0178)
		(property "Reference" "TC5"
			(at 0 0 0)
			(layer "B.SilkS")
			(hide yes)
			(effects
				(font
					(size 1.27 1.27)
				)
				(justify mirror)
			)
		)
		(property "Value" "ST220U10VDM-LGP"
			(at 0 -9.6012 0)
			(unlocked yes)
			(layer "B.Fab")
			(hide yes)
			(effects
				(font
					(size 1.016 1.016)
					(thickness 0.1524)
				)
				(justify mirror)
			)
		)
		(property "Device Type" "CT7343H119"
			(at 0 -11.1252 0)
			(unlocked yes)
			(layer "B.Fab")
			(hide yes)
			(effects
				(font
					(size 1.016 1.016)
					(thickness 0.1524)
				)
				(justify mirror)
			)
		)
		(duplicate_pad_numbers_are_jumpers no)
		(fp_line
			(start -2.286 -4.8768)
			(end 2.286 -4.8768)
			(stroke
				(width 0.1524)
				(type default)
			)
			(layer "B.SilkS")
		)
		(fp_line
			(start -2.286 -2.032)
			(end -2.286 -4.8768)
			(stroke
				(width 0.1524)
				(type default)
			)
			(layer "B.SilkS")
		)
		(fp_line
			(start -2.286 2.032)
			(end -2.286 4.8768)
			(stroke
				(width 0.1524)
				(type default)
			)
			(layer "B.SilkS")
		)
		(fp_line
			(start -2.286 4.8768)
			(end 2.286 4.8768)
			(stroke
				(width 0.1524)
				(type default)
			)
			(layer "B.SilkS")
		)
		(fp_line
			(start -2.1082 -4.699)
			(end 2.1082 -4.699)
			(stroke
				(width 0.508)
				(type default)
			)
			(layer "B.SilkS")
		)
		(fp_line
			(start 2.286 -4.8768)
			(end 2.286 -2.032)
			(stroke
				(width 0.1524)
				(type default)
			)
			(layer "B.SilkS")
		)
		(fp_line
			(start 2.286 4.8768)
			(end 2.286 2.032)
			(stroke
				(width 0.1524)
				(type default)
			)
			(layer "B.SilkS")
		)
		(fp_rect
			(start 2.1463 3.6449)
			(end -2.1463 -3.6449)
			(stroke
				(width 0)
				(type default)
			)
			(fill no)
			(layer "B.CrtYd")
		)
		(fp_poly
			(pts
				(xy 2.54 4.953) (xy 2.54 4.2926) (xy 3.81 4.2926) (xy 3.81 -4.2926) (xy 2.54 -4.2926) (xy 2.54 -4.953)
				(xy -2.54 -4.953) (xy -2.54 -4.2926) (xy -3.81 -4.2926) (xy -3.81 -1.6256) (xy -2.1463 -1.6256)
				(xy -2.1463 -3.6449) (xy 2.1463 -3.6449) (xy 2.1463 3.6449) (xy -2.1463 3.6449) (xy -2.1463 -1.6129)
				(xy -3.81 -1.6129) (xy -3.81 4.2926) (xy -2.54 4.2926) (xy -2.54 4.953)
			)
			(stroke
				(width 0)
				(type default)
			)
			(fill no)
			(layer "B.CrtYd")
		)
		(fp_rect
			(start -2.54 4.2926)
			(end -3.81 -4.2926)
			(stroke
				(width 0)
				(type default)
			)
			(fill no)
			(layer "B.Fab")
		)
		(fp_rect
			(start 2.54 4.953)
			(end -2.54 -4.953)
			(stroke
				(width 0)
				(type default)
			)
			(fill no)
			(layer "B.Fab")
		)
		(fp_rect
			(start 3.81 4.2926)
			(end 2.54 -4.2926)
			(stroke
				(width 0)
				(type default)
			)
			(fill no)
			(layer "B.Fab")
		)
		(pad "1" smd rect
			(at 0 -3.1496 180)
			(size 2.413 2.286)
			(layers "B.Cu" "B.Mask" "B.Paste")
			(net "P5V_A_1")
		)
		(pad "2" smd rect
			(at 0 3.1496 180)
			(size 2.413 2.286)
			(layers "B.Cu" "B.Mask" "B.Paste")
			(net "GND")
		)
		(zone
			(layer "B.Cu")
			(hatch none 0.5)
			(connect_pads
				(clearance 0)
			)
			(min_thickness 0.25)
			(keepout
				(tracks allowed)
				(vias not_allowed)
				(pads allowed)
				(copperpour not_allowed)
				(footprints allowed)
			)
			(placement
				(enabled no)
				(sheetname "")
			)
			(fill
				(thermal_gap 0.5)
				(thermal_bridge_width 0.5)
				(island_removal_mode 0)
			)
			(polygon
				(pts
					(xy 47.1043 -245.7069) (xy 47.1043 -248.6152) (xy 50.1269 -248.6152) (xy 50.1269 -245.7196) (xy 50.1269 -245.3894)
					(xy 47.1043 -245.3894)
				)
			)
		)
		(zone
			(layer "B.Cu")
			(hatch none 0.5)
			(connect_pads
				(clearance 0)
			)
			(min_thickness 0.25)
			(keepout
				(tracks allowed)
				(vias not_allowed)
				(pads allowed)
				(copperpour not_allowed)
				(footprints allowed)
			)
			(placement
				(enabled no)
				(sheetname "")
			)
			(fill
				(thermal_gap 0.5)
				(thermal_bridge_width 0.5)
				(island_removal_mode 0)
			)
			(polygon
				(pts
					(xy 50.1269 -239.4204) (xy 47.1043 -239.4204) (xy 47.1043 -242.316) (xy 47.1043 -242.6462) (xy 50.1269 -242.6462)
					(xy 50.1269 -242.316)
				)
			)
		)
	)
	(footprint ""
		(layer "B.Cu")
		(at 474.462602 -252.40615 -90)
		(property "Reference" "PG14"
			(at 0 0 90)
			(layer "B.SilkS")
			(hide yes)
			(effects
				(font
					(size 1.27 1.27)
				)
				(justify mirror)
			)
		)
		(property "Value" "GAP-CLOSE-PWR-4-GP"
			(at 2.4638 -0.5461 270)
			(unlocked yes)
			(layer "B.Fab")
			(hide yes)
			(effects
				(font
					(size 1.016 1.016)
					(thickness 0.1524)
				)
				(justify mirror)
			)
		)
		(property "Device Type" "GAP-CLOSE-PWR-4"
			(at 2.4638 -2.0701 270)
			(unlocked yes)
			(layer "B.Fab")
			(hide yes)
			(effects
				(font
					(size 1.016 1.016)
					(thickness 0.1524)
				)
				(justify mirror)
			)
		)
		(duplicate_pad_numbers_are_jumpers no)
		(fp_rect
			(start 0.2794 0.254)
			(end -0.2794 -0.254)
			(stroke
				(width 0)
				(type default)
			)
			(fill no)
			(layer "B.CrtYd")
		)
		(fp_rect
			(start 0.2794 0.254)
			(end -0.2794 -0.254)
			(stroke
				(width 0)
				(type default)
			)
			(fill no)
			(layer "B.Fab")
		)
		(pad "1" smd rect
			(at 0.0635 0 90)
			(size 0.1778 0.254)
			(layers "B.Cu" "B.Mask" "B.Paste")
			(net "P5V_A_3")
		)
		(pad "2" smd rect
			(at -0.0635 0 90)
			(size 0.1778 0.254)
			(layers "B.Cu" "B.Mask" "B.Paste")
			(net "P5V_C_CC")
		)
	)
	(footprint ""
		(layer "B.Cu")
		(at 55.431944 -148.253196 180)
		(property "Reference" "R1230"
			(at 0 0 0)
			(layer "B.SilkS")
			(hide yes)
			(effects
				(font
					(size 1.27 1.27)
				)
				(justify mirror)
			)
		)
		(property "Value" "2K7R2F-GP"
			(at -0.064008 -3.993896 180)
			(unlocked yes)
			(layer "B.Fab")
			(hide yes)
			(effects
				(font
					(size 1.016 1.016)
					(thickness 0.1524)
				)
				(justify mirror)
			)
		)
		(property "Device Type" "R402H16"
			(at -0.064008 -5.517896 180)
			(unlocked yes)
			(layer "B.Fab")
			(hide yes)
			(effects
				(font
					(size 1.016 1.016)
					(thickness 0.1524)
				)
				(justify mirror)
			)
		)
		(duplicate_pad_numbers_are_jumpers no)
		(fp_line
			(start 0.508 -0.9398)
			(end 0.508 0.9398)
			(stroke
				(width 0.1524)
				(type default)
			)
			(layer "B.SilkS")
		)
		(fp_line
			(start -0.508 -0.9398)
			(end 0.508 -0.9398)
			(stroke
				(width 0.1524)
				(type default)
			)
			(layer "B.SilkS")
		)
		(fp_rect
			(start 0.508 0.9398)
			(end -0.508 -0.9398)
			(stroke
				(width 0)
				(type default)
			)
			(fill no)
			(layer "B.CrtYd")
		)
		(fp_rect
			(start 0.508 0.9398)
			(end -0.508 -0.9398)
			(stroke
				(width 0)
				(type default)
			)
			(fill no)
			(layer "B.Fab")
		)
		(pad "1" smd custom
			(at 0 -0.4445)
			(size 0.1397 0.1397)
			(layers "B.Cu" "B.Mask" "B.Paste")
			(net "P5V_B_LL")
			(options
				(clearance outline)
				(anchor circle)
			)
			(primitives
				(gr_poly
					(pts
						(arc
							(start -0.1778 0.2794)
							(mid -0.249642 0.249642)
							(end -0.2794 0.1778)
						)
						(arc
							(start -0.2794 -0.1778)
							(mid -0.249642 -0.249642)
							(end -0.1778 -0.2794)
						)
						(arc
							(start 0.1778 -0.2794)
							(mid 0.249642 -0.249642)
							(end 0.2794 -0.1778)
						)
						(arc
							(start 0.2794 0.1778)
							(mid 0.249642 0.249642)
							(end 0.1778 0.2794)
						)
					)
					(width 0)
					(fill yes)
				)
			)
		)
		(pad "2" smd custom
			(at 0 0.4445)
			(size 0.1397 0.1397)
			(layers "B.Cu" "B.Mask" "B.Paste")
			(net "P5V_B_LL_R")
			(options
				(clearance outline)
				(anchor circle)
			)
			(primitives
				(gr_poly
					(pts
						(arc
							(start -0.1778 0.2794)
							(mid -0.249642 0.249642)
							(end -0.2794 0.1778)
						)
						(arc
							(start -0.2794 -0.1778)
							(mid -0.249642 -0.249642)
							(end -0.1778 -0.2794)
						)
						(arc
							(start 0.1778 -0.2794)
							(mid 0.249642 -0.249642)
							(end 0.2794 -0.1778)
						)
						(arc
							(start 0.2794 0.1778)
							(mid 0.249642 0.249642)
							(end 0.1778 0.2794)
						)
					)
					(width 0)
					(fill yes)
				)
			)
		)
	)
)
